(kicad_pcb
	(version 20260206)
	(generator "pcbnew")
	(generator_version "10.0")
	(general
		(thickness 1.6)
		(legacy_teardrops no)
	)
	(paper "A4")
	(title_block
		(title "03242023_DA0F0TMBIJ0_F0T_Motherboard_J_brd_V01_OCP.brd")
		(comment 1 "Grand Teton / footprints 1020-1025 of 6105")
	)
	(layers
		(0 "F.Cu" signal "TOP")
		(4 "In1.Cu" signal "GND")
		(6 "In2.Cu" signal "IN1")
		(8 "In3.Cu" signal "GND1")
		(10 "In4.Cu" signal "IN2")
		(12 "In5.Cu" signal "GND2")
		(14 "In6.Cu" signal "IN3")
		(16 "In7.Cu" signal "GND3")
		(18 "In8.Cu" signal "VCC")
		(20 "In9.Cu" signal "VCC1")
		(22 "In10.Cu" signal "GND4")
		(24 "In11.Cu" signal "IN4")
		(26 "In12.Cu" signal "GND5")
		(28 "In13.Cu" signal "IN5")
		(30 "In14.Cu" signal "GND6")
		(32 "In15.Cu" signal "IN6")
		(34 "In16.Cu" signal "GND7")
		(2 "B.Cu" signal "BOTTOM")
		(9 "F.Adhes" user "F.Adhesive")
		(11 "B.Adhes" user "B.Adhesive")
		(13 "F.Paste" user "Package Geometry/Pastemask Top")
		(15 "B.Paste" user "Package Geometry/Pastemask Bottom")
		(5 "F.SilkS" user "Ref Des/Silkscreen Top")
		(7 "B.SilkS" user "Ref Des/Silkscreen Bottom")
		(1 "F.Mask" user "Board Geometry/Soldermask Top")
		(3 "B.Mask" user "Board Geometry/Soldermask Bottom")
		(17 "Dwgs.User" user "User.Drawings")
		(19 "Cmts.User" user "User.Comments")
		(21 "Eco1.User" user "User.Eco1")
		(23 "Eco2.User" user "User.Eco2")
		(25 "Edge.Cuts" user "Board Geometry/Outline")
		(27 "Margin" user)
		(31 "F.CrtYd" user "Package Geometry/Place Bound Top")
		(29 "B.CrtYd" user "Package Geometry/Place Bound Bottom")
		(35 "F.Fab" user "Ref Des/Assembly Top")
		(33 "B.Fab" user "Ref Des/Assembly Bottom")
	)
	(footprint ""
		(layer "F.Cu")
		(at 374.112282 -57.263792)
		(property "Reference" "R746"
			(at 0 0 0)
			(layer "F.SilkS")
			(hide yes)
			(effects
				(font
					(size 1.27 1.27)
				)
			)
		)
		(property "Value" ""
			(at 0 0 0)
			(layer "F.Fab")
			(effects
				(font
					(size 1.27 1.27)
				)
			)
		)
		(duplicate_pad_numbers_are_jumpers no)
		(fp_line
			(start -0.7874 -0.4064)
			(end 0.7874 -0.4064)
			(stroke
				(width 0.1524)
				(type default)
			)
			(layer "F.SilkS")
		)
		(fp_line
			(start -0.7874 0.4064)
			(end -0.7874 -0.4064)
			(stroke
				(width 0.1524)
				(type default)
			)
			(layer "F.SilkS")
		)
		(fp_line
			(start 0.7874 -0.4064)
			(end 0.7874 0.4064)
			(stroke
				(width 0.1524)
				(type default)
			)
			(layer "F.SilkS")
		)
		(fp_line
			(start 0.7874 0.4064)
			(end -0.7874 0.4064)
			(stroke
				(width 0.1524)
				(type default)
			)
			(layer "F.SilkS")
		)
		(fp_line
			(start -0.67945 -0.305054)
			(end -0.12065 -0.305054)
			(stroke
				(width 0.1)
				(type default)
			)
			(layer "F.Fab")
		)
		(fp_line
			(start -0.67945 0.3048)
			(end -0.67945 -0.305054)
			(stroke
				(width 0.1)
				(type default)
			)
			(layer "F.Fab")
		)
		(fp_line
			(start -0.12065 -0.305054)
			(end -0.12065 -0.2794)
			(stroke
				(width 0.1)
				(type default)
			)
			(layer "F.Fab")
		)
		(fp_line
			(start -0.12065 -0.2794)
			(end 0.12065 -0.2794)
			(stroke
				(width 0.1)
				(type default)
			)
			(layer "F.Fab")
		)
		(fp_line
			(start -0.12065 0.2794)
			(end -0.12065 0.3048)
			(stroke
				(width 0.1)
				(type default)
			)
			(layer "F.Fab")
		)
		(fp_line
			(start -0.12065 0.3048)
			(end -0.67945 0.3048)
			(stroke
				(width 0.1)
				(type default)
			)
			(layer "F.Fab")
		)
		(fp_line
			(start 0.120396 0.2794)
			(end -0.12065 0.2794)
			(stroke
				(width 0.1)
				(type default)
			)
			(layer "F.Fab")
		)
		(fp_line
			(start 0.120396 0.3048)
			(end 0.120396 0.2794)
			(stroke
				(width 0.1)
				(type default)
			)
			(layer "F.Fab")
		)
		(fp_line
			(start 0.12065 -0.3048)
			(end 0.67945 -0.3048)
			(stroke
				(width 0.1)
				(type default)
			)
			(layer "F.Fab")
		)
		(fp_line
			(start 0.12065 -0.2794)
			(end 0.12065 -0.3048)
			(stroke
				(width 0.1)
				(type default)
			)
			(layer "F.Fab")
		)
		(fp_line
			(start 0.67945 -0.3048)
			(end 0.67945 0.3048)
			(stroke
				(width 0.1)
				(type default)
			)
			(layer "F.Fab")
		)
		(fp_line
			(start 0.67945 0.3048)
			(end 0.120396 0.3048)
			(stroke
				(width 0.1)
				(type default)
			)
			(layer "F.Fab")
		)
		(pad "1" smd circle
			(at -0.40005 0)
			(size 0 0)
			(layers "F.Cu" "F.Mask" "F.Paste")
			(net "PD_74CB_A9")
		)
		(pad "2" smd circle
			(at 0.40005 0)
			(size 0 0)
			(layers "F.Cu" "F.Mask" "F.Paste")
			(net "GND")
		)
	)
	(footprint ""
		(layer "F.Cu")
		(at 307.725826 -43.589194 180)
		(property "Reference" "R474"
			(at 0 0 180)
			(layer "F.SilkS")
			(hide yes)
			(effects
				(font
					(size 1.27 1.27)
				)
			)
		)
		(property "Value" ""
			(at 0 0 180)
			(layer "F.Fab")
			(effects
				(font
					(size 1.27 1.27)
				)
			)
		)
		(duplicate_pad_numbers_are_jumpers no)
		(fp_line
			(start 0.7874 0.4064)
			(end -0.7874 0.4064)
			(stroke
				(width 0.1524)
				(type default)
			)
			(layer "F.SilkS")
		)
		(fp_line
			(start 0.7874 -0.4064)
			(end 0.7874 0.4064)
			(stroke
				(width 0.1524)
				(type default)
			)
			(layer "F.SilkS")
		)
		(fp_line
			(start -0.7874 0.4064)
			(end -0.7874 -0.4064)
			(stroke
				(width 0.1524)
				(type default)
			)
			(layer "F.SilkS")
		)
		(fp_line
			(start -0.7874 -0.4064)
			(end 0.7874 -0.4064)
			(stroke
				(width 0.1524)
				(type default)
			)
			(layer "F.SilkS")
		)
		(fp_line
			(start 0.67945 0.3048)
			(end 0.120396 0.3048)
			(stroke
				(width 0.1)
				(type default)
			)
			(layer "F.Fab")
		)
		(fp_line
			(start 0.67945 -0.3048)
			(end 0.67945 0.3048)
			(stroke
				(width 0.1)
				(type default)
			)
			(layer "F.Fab")
		)
		(fp_line
			(start 0.12065 -0.2794)
			(end 0.12065 -0.3048)
			(stroke
				(width 0.1)
				(type default)
			)
			(layer "F.Fab")
		)
		(fp_line
			(start 0.12065 -0.3048)
			(end 0.67945 -0.3048)
			(stroke
				(width 0.1)
				(type default)
			)
			(layer "F.Fab")
		)
		(fp_line
			(start 0.120396 0.3048)
			(end 0.120396 0.2794)
			(stroke
				(width 0.1)
				(type default)
			)
			(layer "F.Fab")
		)
		(fp_line
			(start 0.120396 0.2794)
			(end -0.12065 0.2794)
			(stroke
				(width 0.1)
				(type default)
			)
			(layer "F.Fab")
		)
		(fp_line
			(start -0.12065 0.3048)
			(end -0.67945 0.3048)
			(stroke
				(width 0.1)
				(type default)
			)
			(layer "F.Fab")
		)
		(fp_line
			(start -0.12065 0.2794)
			(end -0.12065 0.3048)
			(stroke
				(width 0.1)
				(type default)
			)
			(layer "F.Fab")
		)
		(fp_line
			(start -0.12065 -0.2794)
			(end 0.12065 -0.2794)
			(stroke
				(width 0.1)
				(type default)
			)
			(layer "F.Fab")
		)
		(fp_line
			(start -0.12065 -0.305054)
			(end -0.12065 -0.2794)
			(stroke
				(width 0.1)
				(type default)
			)
			(layer "F.Fab")
		)
		(fp_line
			(start -0.67945 0.3048)
			(end -0.67945 -0.305054)
			(stroke
				(width 0.1)
				(type default)
			)
			(layer "F.Fab")
		)
		(fp_line
			(start -0.67945 -0.305054)
			(end -0.12065 -0.305054)
			(stroke
				(width 0.1)
				(type default)
			)
			(layer "F.Fab")
		)
		(pad "1" smd circle
			(at -0.40005 0 180)
			(size 0 0)
			(layers "F.Cu" "F.Mask" "F.Paste")
			(net "FM_PCHHOT_N")
		)
		(pad "2" smd circle
			(at 0.40005 0 180)
			(size 0 0)
			(layers "F.Cu" "F.Mask" "F.Paste")
			(net "FM_PCHHOT_R_N")
		)
	)
	(footprint ""
		(layer "F.Cu")
		(at 220.04528 -109.591348)
		(property "Reference" "R1195"
			(at 0 0 0)
			(layer "F.SilkS")
			(hide yes)
			(effects
				(font
					(size 1.27 1.27)
				)
			)
		)
		(property "Value" ""
			(at 0 0 0)
			(layer "F.Fab")
			(effects
				(font
					(size 1.27 1.27)
				)
			)
		)
		(duplicate_pad_numbers_are_jumpers no)
		(fp_line
			(start -0.7874 -0.4064)
			(end 0.7874 -0.4064)
			(stroke
				(width 0.1524)
				(type default)
			)
			(layer "F.SilkS")
		)
		(fp_line
			(start -0.7874 0.4064)
			(end -0.7874 -0.4064)
			(stroke
				(width 0.1524)
				(type default)
			)
			(layer "F.SilkS")
		)
		(fp_line
			(start 0.7874 -0.4064)
			(end 0.7874 0.4064)
			(stroke
				(width 0.1524)
				(type default)
			)
			(layer "F.SilkS")
		)
		(fp_line
			(start 0.7874 0.4064)
			(end -0.7874 0.4064)
			(stroke
				(width 0.1524)
				(type default)
			)
			(layer "F.SilkS")
		)
		(fp_line
			(start -0.67945 -0.305054)
			(end -0.12065 -0.305054)
			(stroke
				(width 0.1)
				(type default)
			)
			(layer "F.Fab")
		)
		(fp_line
			(start -0.67945 0.3048)
			(end -0.67945 -0.305054)
			(stroke
				(width 0.1)
				(type default)
			)
			(layer "F.Fab")
		)
		(fp_line
			(start -0.12065 -0.305054)
			(end -0.12065 -0.2794)
			(stroke
				(width 0.1)
				(type default)
			)
			(layer "F.Fab")
		)
		(fp_line
			(start -0.12065 -0.2794)
			(end 0.12065 -0.2794)
			(stroke
				(width 0.1)
				(type default)
			)
			(layer "F.Fab")
		)
		(fp_line
			(start -0.12065 0.2794)
			(end -0.12065 0.3048)
			(stroke
				(width 0.1)
				(type default)
			)
			(layer "F.Fab")
		)
		(fp_line
			(start -0.12065 0.3048)
			(end -0.67945 0.3048)
			(stroke
				(width 0.1)
				(type default)
			)
			(layer "F.Fab")
		)
		(fp_line
			(start 0.120396 0.2794)
			(end -0.12065 0.2794)
			(stroke
				(width 0.1)
				(type default)
			)
			(layer "F.Fab")
		)
		(fp_line
			(start 0.120396 0.3048)
			(end 0.120396 0.2794)
			(stroke
				(width 0.1)
				(type default)
			)
			(layer "F.Fab")
		)
		(fp_line
			(start 0.12065 -0.3048)
			(end 0.67945 -0.3048)
			(stroke
				(width 0.1)
				(type default)
			)
			(layer "F.Fab")
		)
		(fp_line
			(start 0.12065 -0.2794)
			(end 0.12065 -0.3048)
			(stroke
				(width 0.1)
				(type default)
			)
			(layer "F.Fab")
		)
		(fp_line
			(start 0.67945 -0.3048)
			(end 0.67945 0.3048)
			(stroke
				(width 0.1)
				(type default)
			)
			(layer "F.Fab")
		)
		(fp_line
			(start 0.67945 0.3048)
			(end 0.120396 0.3048)
			(stroke
				(width 0.1)
				(type default)
			)
			(layer "F.Fab")
		)
		(pad "1" smd circle
			(at -0.40005 0)
			(size 0 0)
			(layers "F.Cu" "F.Mask" "F.Paste")
			(net "P3V3_AUX")
		)
		(pad "2" smd circle
			(at 0.40005 0)
			(size 0 0)
			(layers "F.Cu" "F.Mask" "F.Paste")
			(net "PU_PLD_HEARTBEAT_LVC3")
		)
	)
	(footprint ""
		(layer "F.Cu")
		(at 102.845616 -355.773736)
		(property "Reference" "R312"
			(at 0 0 0)
			(layer "F.SilkS")
			(hide yes)
			(effects
				(font
					(size 1.27 1.27)
				)
			)
		)
		(property "Value" ""
			(at 0 0 0)
			(layer "F.Fab")
			(effects
				(font
					(size 1.27 1.27)
				)
			)
		)
		(duplicate_pad_numbers_are_jumpers no)
		(fp_line
			(start -0.7874 -0.4064)
			(end 0.7874 -0.4064)
			(stroke
				(width 0.1524)
				(type default)
			)
			(layer "F.SilkS")
		)
		(fp_line
			(start -0.7874 0.4064)
			(end -0.7874 -0.4064)
			(stroke
				(width 0.1524)
				(type default)
			)
			(layer "F.SilkS")
		)
		(fp_line
			(start 0.7874 -0.4064)
			(end 0.7874 0.4064)
			(stroke
				(width 0.1524)
				(type default)
			)
			(layer "F.SilkS")
		)
		(fp_line
			(start 0.7874 0.4064)
			(end -0.7874 0.4064)
			(stroke
				(width 0.1524)
				(type default)
			)
			(layer "F.SilkS")
		)
		(fp_line
			(start -0.67945 -0.305054)
			(end -0.12065 -0.305054)
			(stroke
				(width 0.1)
				(type default)
			)
			(layer "F.Fab")
		)
		(fp_line
			(start -0.67945 0.3048)
			(end -0.67945 -0.305054)
			(stroke
				(width 0.1)
				(type default)
			)
			(layer "F.Fab")
		)
		(fp_line
			(start -0.12065 -0.305054)
			(end -0.12065 -0.2794)
			(stroke
				(width 0.1)
				(type default)
			)
			(layer "F.Fab")
		)
		(fp_line
			(start -0.12065 -0.2794)
			(end 0.12065 -0.2794)
			(stroke
				(width 0.1)
				(type default)
			)
			(layer "F.Fab")
		)
		(fp_line
			(start -0.12065 0.2794)
			(end -0.12065 0.3048)
			(stroke
				(width 0.1)
				(type default)
			)
			(layer "F.Fab")
		)
		(fp_line
			(start -0.12065 0.3048)
			(end -0.67945 0.3048)
			(stroke
				(width 0.1)
				(type default)
			)
			(layer "F.Fab")
		)
		(fp_line
			(start 0.120396 0.2794)
			(end -0.12065 0.2794)
			(stroke
				(width 0.1)
				(type default)
			)
			(layer "F.Fab")
		)
		(fp_line
			(start 0.120396 0.3048)
			(end 0.120396 0.2794)
			(stroke
				(width 0.1)
				(type default)
			)
			(layer "F.Fab")
		)
		(fp_line
			(start 0.12065 -0.3048)
			(end 0.67945 -0.3048)
			(stroke
				(width 0.1)
				(type default)
			)
			(layer "F.Fab")
		)
		(fp_line
			(start 0.12065 -0.2794)
			(end 0.12065 -0.3048)
			(stroke
				(width 0.1)
				(type default)
			)
			(layer "F.Fab")
		)
		(fp_line
			(start 0.67945 -0.3048)
			(end 0.67945 0.3048)
			(stroke
				(width 0.1)
				(type default)
			)
			(layer "F.Fab")
		)
		(fp_line
			(start 0.67945 0.3048)
			(end 0.120396 0.3048)
			(stroke
				(width 0.1)
				(type default)
			)
			(layer "F.Fab")
		)
		(pad "1" smd circle
			(at -0.40005 0)
			(size 0 0)
			(layers "F.Cu" "F.Mask" "F.Paste")
			(net "SVID_ALERT0_CPU1_R_N")
		)
		(pad "2" smd circle
			(at 0.40005 0)
			(size 0 0)
			(layers "F.Cu" "F.Mask" "F.Paste")
			(net "SVID_ALERT_PVCCIN_CPU1_R")
		)
	)
	(footprint ""
		(layer "F.Cu")
		(at 128.548384 -359.871518 -90)
		(property "Reference" "PC644"
			(at 0 0 270)
			(layer "F.SilkS")
			(hide yes)
			(effects
				(font
					(size 1.27 1.27)
				)
			)
		)
		(property "Value" ""
			(at 0 0 270)
			(layer "F.Fab")
			(effects
				(font
					(size 1.27 1.27)
				)
			)
		)
		(duplicate_pad_numbers_are_jumpers no)
		(fp_line
			(start -0.7874 0.4064)
			(end -0.7874 -0.4064)
			(stroke
				(width 0.1524)
				(type default)
			)
			(layer "F.SilkS")
		)
		(fp_line
			(start 0.7874 0.4064)
			(end -0.7874 0.4064)
			(stroke
				(width 0.1524)
				(type default)
			)
			(layer "F.SilkS")
		)
		(fp_line
			(start -0.7874 -0.4064)
			(end 0.7874 -0.4064)
			(stroke
				(width 0.1524)
				(type default)
			)
			(layer "F.SilkS")
		)
		(fp_line
			(start 0.7874 -0.4064)
			(end 0.7874 0.4064)
			(stroke
				(width 0.1524)
				(type default)
			)
			(layer "F.SilkS")
		)
		(fp_line
			(start -0.67945 0.3048)
			(end -0.67945 -0.305054)
			(stroke
				(width 0.1)
				(type default)
			)
			(layer "F.Fab")
		)
		(fp_line
			(start -0.12065 0.3048)
			(end -0.67945 0.3048)
			(stroke
				(width 0.1)
				(type default)
			)
			(layer "F.Fab")
		)
		(fp_line
			(start 0.120396 0.3048)
			(end 0.120396 0.2794)
			(stroke
				(width 0.1)
				(type default)
			)
			(layer "F.Fab")
		)
		(fp_line
			(start 0.67945 0.3048)
			(end 0.120396 0.3048)
			(stroke
				(width 0.1)
				(type default)
			)
			(layer "F.Fab")
		)
		(fp_line
			(start -0.12065 0.2794)
			(end -0.12065 0.3048)
			(stroke
				(width 0.1)
				(type default)
			)
			(layer "F.Fab")
		)
		(fp_line
			(start 0.120396 0.2794)
			(end -0.12065 0.2794)
			(stroke
				(width 0.1)
				(type default)
			)
			(layer "F.Fab")
		)
		(fp_line
			(start -0.12065 -0.2794)
			(end 0.12065 -0.2794)
			(stroke
				(width 0.1)
				(type default)
			)
			(layer "F.Fab")
		)
		(fp_line
			(start 0.12065 -0.2794)
			(end 0.12065 -0.3048)
			(stroke
				(width 0.1)
				(type default)
			)
			(layer "F.Fab")
		)
		(fp_line
			(start 0.12065 -0.3048)
			(end 0.67945 -0.3048)
			(stroke
				(width 0.1)
				(type default)
			)
			(layer "F.Fab")
		)
		(fp_line
			(start 0.67945 -0.3048)
			(end 0.67945 0.3048)
			(stroke
				(width 0.1)
				(type default)
			)
			(layer "F.Fab")
		)
		(fp_line
			(start -0.67945 -0.305054)
			(end -0.12065 -0.305054)
			(stroke
				(width 0.1)
				(type default)
			)
			(layer "F.Fab")
		)
		(fp_line
			(start -0.12065 -0.305054)
			(end -0.12065 -0.2794)
			(stroke
				(width 0.1)
				(type default)
			)
			(layer "F.Fab")
		)
		(pad "1" smd circle
			(at -0.40005 0 270)
			(size 0 0)
			(layers "F.Cu" "F.Mask" "F.Paste")
			(net "PVPP_HBM_CPU1_VCC")
		)
		(pad "2" smd circle
			(at 0.40005 0 270)
			(size 0 0)
			(layers "F.Cu" "F.Mask" "F.Paste")
			(net "GND")
		)
	)
	(footprint ""
		(layer "F.Cu")
		(at 213.54288 -32.857948 180)
		(property "Reference" "R3577"
			(at 0 0 180)
			(layer "F.SilkS")
			(hide yes)
			(effects
				(font
					(size 1.27 1.27)
				)
			)
		)
		(property "Value" ""
			(at 0 0 180)
			(layer "F.Fab")
			(effects
				(font
					(size 1.27 1.27)
				)
			)
		)
		(duplicate_pad_numbers_are_jumpers no)
		(fp_line
			(start 0.7874 0.4064)
			(end -0.7874 0.4064)
			(stroke
				(width 0.1524)
				(type default)
			)
			(layer "F.SilkS")
		)
		(fp_line
			(start 0.7874 -0.4064)
			(end 0.7874 0.4064)
			(stroke
				(width 0.1524)
				(type default)
			)
			(layer "F.SilkS")
		)
		(fp_line
			(start -0.7874 0.4064)
			(end -0.7874 -0.4064)
			(stroke
				(width 0.1524)
				(type default)
			)
			(layer "F.SilkS")
		)
		(fp_line
			(start -0.7874 -0.4064)
			(end 0.7874 -0.4064)
			(stroke
				(width 0.1524)
				(type default)
			)
			(layer "F.SilkS")
		)
		(fp_line
			(start 0.67945 0.3048)
			(end 0.120396 0.3048)
			(stroke
				(width 0.1)
				(type default)
			)
			(layer "F.Fab")
		)
		(fp_line
			(start 0.67945 -0.3048)
			(end 0.67945 0.3048)
			(stroke
				(width 0.1)
				(type default)
			)
			(layer "F.Fab")
		)
		(fp_line
			(start 0.12065 -0.2794)
			(end 0.12065 -0.3048)
			(stroke
				(width 0.1)
				(type default)
			)
			(layer "F.Fab")
		)
		(fp_line
			(start 0.12065 -0.3048)
			(end 0.67945 -0.3048)
			(stroke
				(width 0.1)
				(type default)
			)
			(layer "F.Fab")
		)
		(fp_line
			(start 0.120396 0.3048)
			(end 0.120396 0.2794)
			(stroke
				(width 0.1)
				(type default)
			)
			(layer "F.Fab")
		)
		(fp_line
			(start 0.120396 0.2794)
			(end -0.12065 0.2794)
			(stroke
				(width 0.1)
				(type default)
			)
			(layer "F.Fab")
		)
		(fp_line
			(start -0.12065 0.3048)
			(end -0.67945 0.3048)
			(stroke
				(width 0.1)
				(type default)
			)
			(layer "F.Fab")
		)
		(fp_line
			(start -0.12065 0.2794)
			(end -0.12065 0.3048)
			(stroke
				(width 0.1)
				(type default)
			)
			(layer "F.Fab")
		)
		(fp_line
			(start -0.12065 -0.2794)
			(end 0.12065 -0.2794)
			(stroke
				(width 0.1)
				(type default)
			)
			(layer "F.Fab")
		)
		(fp_line
			(start -0.12065 -0.305054)
			(end -0.12065 -0.2794)
			(stroke
				(width 0.1)
				(type default)
			)
			(layer "F.Fab")
		)
		(fp_line
			(start -0.67945 0.3048)
			(end -0.67945 -0.305054)
			(stroke
				(width 0.1)
				(type default)
			)
			(layer "F.Fab")
		)
		(fp_line
			(start -0.67945 -0.305054)
			(end -0.12065 -0.305054)
			(stroke
				(width 0.1)
				(type default)
			)
			(layer "F.Fab")
		)
		(pad "1" smd circle
			(at -0.40005 0 180)
			(size 0 0)
			(layers "F.Cu" "F.Mask" "F.Paste")
			(net "SMB_INA230_5_3V3AUX_SDA_R")
		)
		(pad "2" smd circle
			(at 0.40005 0 180)
			(size 0 0)
			(layers "F.Cu" "F.Mask" "F.Paste")
			(net "SMB_INA230_5_3V3AUX_SDA_R1")
		)
	)
)
